(kicad_pcb
	(version 20260206)
	(generator "pcbnew")
	(generator_version "10.0")
	(general
		(thickness 1.6)
		(legacy_teardrops no)
	)
	(paper "A4")
	(title_block
		(title "Wiwynn_Tioga_Pass_MB.brd")
		(comment 1 "Tioga Pass / footprints 4052-4058 of 4770")
	)
	(layers
		(0 "F.Cu" signal "TOP")
		(4 "In1.Cu" signal "L2GND")
		(6 "In2.Cu" signal "L3")
		(8 "In3.Cu" signal "L4GND")
		(10 "In4.Cu" signal "L5")
		(12 "In5.Cu" signal "L6GND")
		(14 "In6.Cu" signal "L7VCC")
		(16 "In7.Cu" signal "L8VCC")
		(18 "In8.Cu" signal "L9GND")
		(20 "In9.Cu" signal "L10")
		(22 "In10.Cu" signal "L11GND")
		(24 "In11.Cu" signal "L12")
		(26 "In12.Cu" signal "L13GND")
		(2 "B.Cu" signal "BOTTOM")
		(9 "F.Adhes" user "F.Adhesive")
		(11 "B.Adhes" user "B.Adhesive")
		(13 "F.Paste" user "Package Geometry/Pastemask Top")
		(15 "B.Paste" user "Package Geometry/Pastemask Bottom")
		(5 "F.SilkS" user "Ref Des/Silkscreen Top")
		(7 "B.SilkS" user "Ref Des/Silkscreen Bottom")
		(1 "F.Mask" user "Board Geometry/Soldermask Top")
		(3 "B.Mask" user "Board Geometry/Soldermask Bottom")
		(17 "Dwgs.User" user "User.Drawings")
		(19 "Cmts.User" user "User.Comments")
		(21 "Eco1.User" user "User.Eco1")
		(23 "Eco2.User" user "User.Eco2")
		(25 "Edge.Cuts" user "Board Geometry/Outline")
		(27 "Margin" user)
		(31 "F.CrtYd" user "Package Geometry/Place Bound Top")
		(29 "B.CrtYd" user "Package Geometry/Place Bound Bottom")
		(35 "F.Fab" user "Ref Des/Assembly Top")
		(33 "B.Fab" user "Ref Des/Assembly Bottom")
	)
	(footprint ""
		(layer "B.Cu")
		(at 340.331806 -60.368434)
		(property "Reference" "R2U19"
			(at 0 0 0)
			(layer "B.SilkS")
			(hide yes)
			(effects
				(font
					(size 1.27 1.27)
				)
				(justify mirror)
			)
		)
		(property "Value" ""
			(at 0 0 0)
			(layer "B.Fab")
			(effects
				(font
					(size 1.27 1.27)
				)
				(justify mirror)
			)
		)
		(duplicate_pad_numbers_are_jumpers no)
		(fp_poly
			(pts
				(xy 0.2794 -0.1016) (xy -0.2794 -0.1016) (xy -0.2794 0.9906) (xy 0.2794 0.9906)
			)
			(stroke
				(width 0)
				(type default)
			)
			(fill no)
			(layer "B.CrtYd")
		)
		(fp_line
			(start -0.2794 -0.1016)
			(end 0.2794 -0.1016)
			(stroke
				(width 0.1)
				(type default)
			)
			(layer "B.Fab")
		)
		(fp_line
			(start -0.2794 0.9906)
			(end -0.2794 -0.1016)
			(stroke
				(width 0.1)
				(type default)
			)
			(layer "B.Fab")
		)
		(fp_line
			(start 0.2794 -0.1016)
			(end 0.2794 0.9906)
			(stroke
				(width 0.1)
				(type default)
			)
			(layer "B.Fab")
		)
		(fp_line
			(start 0.2794 0.9906)
			(end -0.2794 0.9906)
			(stroke
				(width 0.1)
				(type default)
			)
			(layer "B.Fab")
		)
		(pad "1" smd rect
			(at 0 0 180)
			(size 0.508 0.508)
			(layers "B.Cu" "B.Mask" "B.Paste")
			(net "P3E_CPU0_PE1_SS_RXN<2>")
		)
		(pad "2" smd rect
			(at 0 0.889 180)
			(size 0.508 0.508)
			(layers "B.Cu" "B.Mask" "B.Paste")
			(net "P3E_CPU0_PE1_SS_R_RXN<2>")
		)
		(zone
			(layer "B.Cu")
			(hatch none 0.5)
			(connect_pads
				(clearance 0)
			)
			(min_thickness 0.25)
			(keepout
				(tracks allowed)
				(vias not_allowed)
				(pads allowed)
				(copperpour not_allowed)
				(footprints allowed)
			)
			(placement
				(enabled no)
				(sheetname "")
			)
			(fill
				(thermal_gap 0.5)
				(thermal_bridge_width 0.5)
				(island_removal_mode 0)
			)
			(polygon
				(pts
					(xy 340.585806 -60.114434) (xy 340.077806 -60.114434) (xy 340.077806 -59.733434) (xy 340.585806 -59.733434)
				)
			)
		)
		(zone
			(layer "B.Cu")
			(hatch none 0.5)
			(connect_pads
				(clearance 0)
			)
			(min_thickness 0.25)
			(keepout
				(tracks not_allowed)
				(vias allowed)
				(pads allowed)
				(copperpour not_allowed)
				(footprints allowed)
			)
			(placement
				(enabled no)
				(sheetname "")
			)
			(fill
				(thermal_gap 0.5)
				(thermal_bridge_width 0.5)
				(island_removal_mode 0)
			)
			(polygon
				(pts
					(xy 340.585806 -59.733434) (xy 340.077806 -59.733434) (xy 340.077806 -60.114434) (xy 340.585806 -60.114434)
				)
			)
		)
	)
	(footprint ""
		(layer "B.Cu")
		(at 365.506 -79.0956 -90)
		(property "Reference" "R7D37"
			(at 0 0 90)
			(layer "B.SilkS")
			(hide yes)
			(effects
				(font
					(size 1.27 1.27)
				)
				(justify mirror)
			)
		)
		(property "Value" ""
			(at 0 0 90)
			(layer "B.Fab")
			(effects
				(font
					(size 1.27 1.27)
				)
				(justify mirror)
			)
		)
		(duplicate_pad_numbers_are_jumpers no)
		(fp_poly
			(pts
				(xy 0.2794 -0.1016) (xy -0.2794 -0.1016) (xy -0.2794 0.9906) (xy 0.2794 0.9906)
			)
			(stroke
				(width 0)
				(type default)
			)
			(fill no)
			(layer "B.CrtYd")
		)
		(fp_line
			(start -0.2794 0.9906)
			(end -0.2794 -0.1016)
			(stroke
				(width 0.1)
				(type default)
			)
			(layer "B.Fab")
		)
		(fp_line
			(start 0.2794 0.9906)
			(end -0.2794 0.9906)
			(stroke
				(width 0.1)
				(type default)
			)
			(layer "B.Fab")
		)
		(fp_line
			(start -0.2794 -0.1016)
			(end 0.2794 -0.1016)
			(stroke
				(width 0.1)
				(type default)
			)
			(layer "B.Fab")
		)
		(fp_line
			(start 0.2794 -0.1016)
			(end 0.2794 0.9906)
			(stroke
				(width 0.1)
				(type default)
			)
			(layer "B.Fab")
		)
		(pad "1" smd rect
			(at 0 0 90)
			(size 0.508 0.508)
			(layers "B.Cu" "B.Mask" "B.Paste")
			(net "FM_CPU1_VRM_OSC_EN")
		)
		(pad "2" smd rect
			(at 0 0.889 90)
			(size 0.508 0.508)
			(layers "B.Cu" "B.Mask" "B.Paste")
			(net "FM_CPU1_VRM_322M_156M_OSC_EN")
		)
		(zone
			(layer "B.Cu")
			(hatch none 0.5)
			(connect_pads
				(clearance 0)
			)
			(min_thickness 0.25)
			(keepout
				(tracks not_allowed)
				(vias allowed)
				(pads allowed)
				(copperpour not_allowed)
				(footprints allowed)
			)
			(placement
				(enabled no)
				(sheetname "")
			)
			(fill
				(thermal_gap 0.5)
				(thermal_bridge_width 0.5)
				(island_removal_mode 0)
			)
			(polygon
				(pts
					(xy 364.871 -78.8416) (xy 364.871 -79.3496) (xy 365.252 -79.3496) (xy 365.252 -78.8416)
				)
			)
		)
		(zone
			(layer "B.Cu")
			(hatch none 0.5)
			(connect_pads
				(clearance 0)
			)
			(min_thickness 0.25)
			(keepout
				(tracks allowed)
				(vias not_allowed)
				(pads allowed)
				(copperpour not_allowed)
				(footprints allowed)
			)
			(placement
				(enabled no)
				(sheetname "")
			)
			(fill
				(thermal_gap 0.5)
				(thermal_bridge_width 0.5)
				(island_removal_mode 0)
			)
			(polygon
				(pts
					(xy 365.252 -78.8416) (xy 365.252 -79.3496) (xy 364.871 -79.3496) (xy 364.871 -78.8416)
				)
			)
		)
	)
	(footprint ""
		(layer "B.Cu")
		(at 21.209 -60.9092)
		(property "Reference" "EU9R1"
			(at -2.159 -1.67513 0)
			(unlocked yes)
			(layer "B.SilkS")
			(effects
				(font
					(size 0.7874 0.5842)
					(thickness 0.1524)
				)
				(justify mirror)
			)
		)
		(property "Value" ""
			(at 0 0 0)
			(layer "B.Fab")
			(effects
				(font
					(size 1.27 1.27)
				)
				(justify mirror)
			)
		)
		(duplicate_pad_numbers_are_jumpers no)
		(fp_line
			(start -4.8006 -0.7493)
			(end -4.8006 -0.635254)
			(stroke
				(width 0.1524)
				(type default)
			)
			(layer "B.SilkS")
		)
		(fp_line
			(start -4.8006 4.5593)
			(end -4.8006 4.445254)
			(stroke
				(width 0.1524)
				(type default)
			)
			(layer "B.SilkS")
		)
		(fp_line
			(start -0.4064 -0.7493)
			(end -4.8006 -0.7493)
			(stroke
				(width 0.1524)
				(type default)
			)
			(layer "B.SilkS")
		)
		(fp_line
			(start -0.4064 -0.635254)
			(end -0.4064 -0.7493)
			(stroke
				(width 0.1524)
				(type default)
			)
			(layer "B.SilkS")
		)
		(fp_line
			(start -0.4064 4.445254)
			(end -0.4064 4.5593)
			(stroke
				(width 0.1524)
				(type default)
			)
			(layer "B.SilkS")
		)
		(fp_line
			(start -0.4064 4.5593)
			(end -4.8006 4.5593)
			(stroke
				(width 0.1524)
				(type default)
			)
			(layer "B.SilkS")
		)
		(fp_circle
			(center 1.076706 -0.704342)
			(end 1.203706 -0.704342)
			(stroke
				(width 0.254)
				(type default)
			)
			(fill no)
			(layer "B.SilkS")
		)
		(fp_rect
			(start -4.8006 4.5593)
			(end -0.4064 -0.7493)
			(stroke
				(width 0)
				(type default)
			)
			(fill no)
			(layer "B.CrtYd")
		)
		(fp_line
			(start -4.8006 -0.7493)
			(end -4.8006 4.5593)
			(stroke
				(width 0.1)
				(type default)
			)
			(layer "B.Fab")
		)
		(fp_line
			(start -4.8006 4.5593)
			(end -0.4064 4.5593)
			(stroke
				(width 0.1)
				(type default)
			)
			(layer "B.Fab")
		)
		(fp_line
			(start -0.4064 -0.7493)
			(end -4.8006 -0.7493)
			(stroke
				(width 0.1)
				(type default)
			)
			(layer "B.Fab")
		)
		(fp_line
			(start -0.4064 4.5593)
			(end -0.4064 -0.7493)
			(stroke
				(width 0.1)
				(type default)
			)
			(layer "B.Fab")
		)
		(fp_circle
			(center 1.076706 -0.704342)
			(end 1.203706 -0.704342)
			(stroke
				(width 0.254)
				(type default)
			)
			(fill no)
			(layer "B.Fab")
		)
		(pad "1" smd rect
			(at 0 0 180)
			(size 1.651 0.508)
			(layers "B.Cu" "B.Mask" "B.Paste")
			(net "P12V_STBY")
		)
		(pad "2" smd rect
			(at 0 1.27 180)
			(size 1.651 0.508)
			(layers "B.Cu" "B.Mask" "B.Paste")
			(net "P12V_STBY")
		)
		(pad "3" smd rect
			(at 0 2.54 180)
			(size 1.651 0.508)
			(layers "B.Cu" "B.Mask" "B.Paste")
			(net "P12V_STBY")
		)
		(pad "4" smd rect
			(at 0 3.81 180)
			(size 1.651 0.508)
			(layers "B.Cu" "B.Mask" "B.Paste")
			(net "A_HSC_GATE2_R")
		)
		(pad "5" smd custom
			(at -3.937 1.905 180)
			(size 1.04775 1.04775)
			(layers "B.Cu" "B.Mask" "B.Paste")
			(net "P12V_MB0_SW")
			(options
				(clearance outline)
				(anchor circle)
			)
			(primitives
				(gr_poly
					(pts
						(xy -2.0955 1.651) (xy -2.0955 -1.651) (xy 0.4445 -1.651) (xy 0.4445 -2.2098) (xy 2.0955 -2.2098)
						(xy 2.0955 2.2098) (xy 0.4445 2.2098) (xy 0.4445 1.651)
					)
					(width 0)
					(fill yes)
				)
			)
		)
	)
	(footprint ""
		(layer "B.Cu")
		(at 183.515 -72.8472)
		(property "Reference" "R6P28"
			(at 0 0 0)
			(layer "B.SilkS")
			(hide yes)
			(effects
				(font
					(size 1.27 1.27)
				)
				(justify mirror)
			)
		)
		(property "Value" ""
			(at 0 0 0)
			(layer "B.Fab")
			(effects
				(font
					(size 1.27 1.27)
				)
				(justify mirror)
			)
		)
		(duplicate_pad_numbers_are_jumpers no)
		(fp_rect
			(start -0.2794 0.9906)
			(end 0.2794 -0.1016)
			(stroke
				(width 0)
				(type default)
			)
			(fill no)
			(layer "B.CrtYd")
		)
		(fp_line
			(start -0.2794 -0.1016)
			(end 0.2794 -0.1016)
			(stroke
				(width 0.1)
				(type default)
			)
			(layer "B.Fab")
		)
		(fp_line
			(start -0.2794 0.9906)
			(end -0.2794 -0.1016)
			(stroke
				(width 0.1)
				(type default)
			)
			(layer "B.Fab")
		)
		(fp_line
			(start 0.2794 -0.1016)
			(end 0.2794 0.9906)
			(stroke
				(width 0.1)
				(type default)
			)
			(layer "B.Fab")
		)
		(fp_line
			(start 0.2794 0.9906)
			(end -0.2794 0.9906)
			(stroke
				(width 0.1)
				(type default)
			)
			(layer "B.Fab")
		)
		(pad "1" smd rect
			(at 0 0 180)
			(size 0.508 0.508)
			(layers "B.Cu" "B.Mask" "B.Paste")
			(net "VR_PVCCIN_CPU0_XADDR1")
		)
		(pad "2" smd rect
			(at 0 0.889 180)
			(size 0.508 0.508)
			(layers "B.Cu" "B.Mask" "B.Paste")
			(net "GND")
		)
		(zone
			(layer "B.Cu")
			(hatch none 0.5)
			(connect_pads
				(clearance 0)
			)
			(min_thickness 0.25)
			(keepout
				(tracks not_allowed)
				(vias allowed)
				(pads allowed)
				(copperpour not_allowed)
				(footprints allowed)
			)
			(placement
				(enabled no)
				(sheetname "")
			)
			(fill
				(thermal_gap 0.5)
				(thermal_bridge_width 0.5)
				(island_removal_mode 0)
			)
			(polygon
				(pts
					(xy 183.261 -72.2122) (xy 183.769 -72.2122) (xy 183.769 -72.5932) (xy 183.261 -72.5932)
				)
			)
		)
		(zone
			(layer "B.Cu")
			(hatch none 0.5)
			(connect_pads
				(clearance 0)
			)
			(min_thickness 0.25)
			(keepout
				(tracks allowed)
				(vias not_allowed)
				(pads allowed)
				(copperpour not_allowed)
				(footprints allowed)
			)
			(placement
				(enabled no)
				(sheetname "")
			)
			(fill
				(thermal_gap 0.5)
				(thermal_bridge_width 0.5)
				(island_removal_mode 0)
			)
			(polygon
				(pts
					(xy 183.261 -72.2122) (xy 183.769 -72.2122) (xy 183.769 -72.5932) (xy 183.261 -72.5932)
				)
			)
		)
	)
	(footprint ""
		(layer "B.Cu")
		(at 100.6983 -135.4074 90)
		(property "Reference" "C8M2"
			(at 0 0 90)
			(layer "B.SilkS")
			(hide yes)
			(effects
				(font
					(size 1.27 1.27)
				)
				(justify mirror)
			)
		)
		(property "Value" ""
			(at 0 0 90)
			(layer "B.Fab")
			(effects
				(font
					(size 1.27 1.27)
				)
				(justify mirror)
			)
		)
		(duplicate_pad_numbers_are_jumpers no)
		(fp_rect
			(start 0.500126 1.598422)
			(end -0.500126 -0.201422)
			(stroke
				(width 0)
				(type default)
			)
			(fill no)
			(layer "B.CrtYd")
		)
		(fp_line
			(start 0.500126 -0.201422)
			(end -0.500126 -0.201422)
			(stroke
				(width 0.1)
				(type default)
			)
			(layer "B.Fab")
		)
		(fp_line
			(start -0.500126 -0.201422)
			(end -0.500126 1.598422)
			(stroke
				(width 0.1)
				(type default)
			)
			(layer "B.Fab")
		)
		(fp_line
			(start 0.500126 1.598422)
			(end 0.500126 -0.201422)
			(stroke
				(width 0.1)
				(type default)
			)
			(layer "B.Fab")
		)
		(fp_line
			(start -0.500126 1.598422)
			(end 0.500126 1.598422)
			(stroke
				(width 0.1)
				(type default)
			)
			(layer "B.Fab")
		)
		(pad "1" smd rect
			(at 0 0)
			(size 0.889 0.9906)
			(layers "B.Cu" "B.Mask" "B.Paste")
			(net "PVDDQ_KLM")
		)
		(pad "2" smd rect
			(at 0 1.397)
			(size 0.889 0.9906)
			(layers "B.Cu" "B.Mask" "B.Paste")
			(net "GND")
		)
		(zone
			(layer "B.Cu")
			(hatch none 0.5)
			(connect_pads
				(clearance 0)
			)
			(min_thickness 0.25)
			(keepout
				(tracks allowed)
				(vias not_allowed)
				(pads allowed)
				(copperpour not_allowed)
				(footprints allowed)
			)
			(placement
				(enabled no)
				(sheetname "")
			)
			(fill
				(thermal_gap 0.5)
				(thermal_bridge_width 0.5)
				(island_removal_mode 0)
			)
			(polygon
				(pts
					(xy 101.6508 -135.9027) (xy 101.1428 -135.9027) (xy 101.1428 -134.9121) (xy 101.6508 -134.9121)
				)
			)
		)
		(zone
			(layer "B.Cu")
			(hatch none 0.5)
			(connect_pads
				(clearance 0)
			)
			(min_thickness 0.25)
			(keepout
				(tracks not_allowed)
				(vias allowed)
				(pads allowed)
				(copperpour not_allowed)
				(footprints allowed)
			)
			(placement
				(enabled no)
				(sheetname "")
			)
			(fill
				(thermal_gap 0.5)
				(thermal_bridge_width 0.5)
				(island_removal_mode 0)
			)
			(polygon
				(pts
					(xy 101.6508 -135.9027) (xy 101.1428 -135.9027) (xy 101.1428 -134.9121) (xy 101.6508 -134.9121)
				)
			)
		)
	)
	(footprint ""
		(layer "B.Cu")
		(at 367.820956 -122.560842 -90)
		(property "Reference" "R784"
			(at 0.8382 -0.67818 270)
			(unlocked yes)
			(layer "B.SilkS")
			(effects
				(font
					(size 0.4064 0.254)
					(thickness 0.1524)
				)
				(justify left mirror)
			)
		)
		(property "Value" ""
			(at 0 0 90)
			(layer "B.Fab")
			(effects
				(font
					(size 1.27 1.27)
				)
				(justify mirror)
			)
		)
		(duplicate_pad_numbers_are_jumpers no)
		(fp_poly
			(pts
				(xy 0.2794 -0.1016) (xy -0.2794 -0.1016) (xy -0.2794 0.9906) (xy 0.2794 0.9906)
			)
			(stroke
				(width 0)
				(type default)
			)
			(fill no)
			(layer "B.CrtYd")
		)
		(fp_line
			(start -0.2794 0.9906)
			(end -0.2794 -0.1016)
			(stroke
				(width 0.1)
				(type default)
			)
			(layer "B.Fab")
		)
		(fp_line
			(start 0.2794 0.9906)
			(end -0.2794 0.9906)
			(stroke
				(width 0.1)
				(type default)
			)
			(layer "B.Fab")
		)
		(fp_line
			(start -0.2794 -0.1016)
			(end 0.2794 -0.1016)
			(stroke
				(width 0.1)
				(type default)
			)
			(layer "B.Fab")
		)
		(fp_line
			(start 0.2794 -0.1016)
			(end 0.2794 0.9906)
			(stroke
				(width 0.1)
				(type default)
			)
			(layer "B.Fab")
		)
		(pad "1" smd rect
			(at 0 0 90)
			(size 0.508 0.508)
			(layers "B.Cu" "B.Mask" "B.Paste")
			(net "P3E_CPU0_PE1_PCH_RXN<8>")
		)
		(pad "2" smd rect
			(at 0 0.889 90)
			(size 0.508 0.508)
			(layers "B.Cu" "B.Mask" "B.Paste")
			(net "P3E_CPU0_PE1_PCH_CON_RXN<8>")
		)
		(zone
			(layer "B.Cu")
			(hatch none 0.5)
			(connect_pads
				(clearance 0)
			)
			(min_thickness 0.25)
			(keepout
				(tracks not_allowed)
				(vias allowed)
				(pads allowed)
				(copperpour not_allowed)
				(footprints allowed)
			)
			(placement
				(enabled no)
				(sheetname "")
			)
			(fill
				(thermal_gap 0.5)
				(thermal_bridge_width 0.5)
				(island_removal_mode 0)
			)
			(polygon
				(pts
					(xy 367.185956 -122.306842) (xy 367.185956 -122.814842) (xy 367.566956 -122.814842) (xy 367.566956 -122.306842)
				)
			)
		)
		(zone
			(layer "B.Cu")
			(hatch none 0.5)
			(connect_pads
				(clearance 0)
			)
			(min_thickness 0.25)
			(keepout
				(tracks allowed)
				(vias not_allowed)
				(pads allowed)
				(copperpour not_allowed)
				(footprints allowed)
			)
			(placement
				(enabled no)
				(sheetname "")
			)
			(fill
				(thermal_gap 0.5)
				(thermal_bridge_width 0.5)
				(island_removal_mode 0)
			)
			(polygon
				(pts
					(xy 367.566956 -122.306842) (xy 367.566956 -122.814842) (xy 367.185956 -122.814842) (xy 367.185956 -122.306842)
				)
			)
		)
	)
	(footprint ""
		(layer "B.Cu")
		(at 162.179 -70.358 180)
		(property "Reference" "R7P18"
			(at 0 0 0)
			(layer "B.SilkS")
			(hide yes)
			(effects
				(font
					(size 1.27 1.27)
				)
				(justify mirror)
			)
		)
		(property "Value" ""
			(at 0 0 0)
			(layer "B.Fab")
			(effects
				(font
					(size 1.27 1.27)
				)
				(justify mirror)
			)
		)
		(duplicate_pad_numbers_are_jumpers no)
		(fp_poly
			(pts
				(xy 0.2794 -0.1016) (xy -0.2794 -0.1016) (xy -0.2794 0.9906) (xy 0.2794 0.9906)
			)
			(stroke
				(width 0)
				(type default)
			)
			(fill no)
			(layer "B.CrtYd")
		)
		(fp_line
			(start 0.2794 0.9906)
			(end -0.2794 0.9906)
			(stroke
				(width 0.1)
				(type default)
			)
			(layer "B.Fab")
		)
		(fp_line
			(start 0.2794 -0.1016)
			(end 0.2794 0.9906)
			(stroke
				(width 0.1)
				(type default)
			)
			(layer "B.Fab")
		)
		(fp_line
			(start -0.2794 0.9906)
			(end -0.2794 -0.1016)
			(stroke
				(width 0.1)
				(type default)
			)
			(layer "B.Fab")
		)
		(fp_line
			(start -0.2794 -0.1016)
			(end 0.2794 -0.1016)
			(stroke
				(width 0.1)
				(type default)
			)
			(layer "B.Fab")
		)
		(pad "1" smd rect
			(at 0 0)
			(size 0.508 0.508)
			(layers "B.Cu" "B.Mask" "B.Paste")
			(net "PVCCIO_CPU0")
		)
		(pad "2" smd rect
			(at 0 0.889)
			(size 0.508 0.508)
			(layers "B.Cu" "B.Mask" "B.Paste")
			(net "H_CPU1_CATERR_G_N")
		)
		(zone
			(layer "B.Cu")
			(hatch none 0.5)
			(connect_pads
				(clearance 0)
			)
			(min_thickness 0.25)
			(keepout
				(tracks not_allowed)
				(vias allowed)
				(pads allowed)
				(copperpour not_allowed)
				(footprints allowed)
			)
			(placement
				(enabled no)
				(sheetname "")
			)
			(fill
				(thermal_gap 0.5)
				(thermal_bridge_width 0.5)
				(island_removal_mode 0)
			)
			(polygon
				(pts
					(xy 161.925 -70.993) (xy 162.433 -70.993) (xy 162.433 -70.612) (xy 161.925 -70.612)
				)
			)
		)
		(zone
			(layer "B.Cu")
			(hatch none 0.5)
			(connect_pads
				(clearance 0)
			)
			(min_thickness 0.25)
			(keepout
				(tracks allowed)
				(vias not_allowed)
				(pads allowed)
				(copperpour not_allowed)
				(footprints allowed)
			)
			(placement
				(enabled no)
				(sheetname "")
			)
			(fill
				(thermal_gap 0.5)
				(thermal_bridge_width 0.5)
				(island_removal_mode 0)
			)
			(polygon
				(pts
					(xy 161.925 -70.612) (xy 162.433 -70.612) (xy 162.433 -70.993) (xy 161.925 -70.993)
				)
			)
		)
	)
)
